# S9S_MB_2U (Grand Teton) — schematic netlist excerpt (pin names and nets, part order shuffled) for the footprints in the layout excerpt that follows; sources: Cadence DE-HDL packaged netlist, KiCad conversion of 03242023_DA0F0TMBIJ0_F0T_Motherboard_J_brd_V01_OCP.brd

R260  Q_RES  240 1% CHIP  pkg 0402LF  page 120 : A = PVNN_TERM_CPU1 ; B = FM_S3M_CPU1_LVC1_GPIO_3
C169  Q_CAP_DIFFBUS  DIFF BUS_0.22UF 6.3V 20% X6S  pkg C0201  page 178 : \1\ = DMI_CPU0_PCH_RX_C_DN<0> ; \2\ = DMI_CPU0_PCH_RX_DN<0>
C2322  Q_CAP  1UF 25V 10% EMPTY  pkg C0402  page 196 : A = P3V3_AUX_USB_HUB_2 ; B = GND

(kicad_pcb
	(version 20260206)
	(generator "pcbnew")
	(generator_version "10.0")
	(general
		(thickness 1.6)
		(legacy_teardrops no)
	)
	(paper "A4")
	(title_block
		(title "03242023_DA0F0TMBIJ0_F0T_Motherboard_J_brd_V01_OCP.brd")
		(comment 1 "Grand Teton / footprints 4430-4432 of 6105")
	)
	(layers
		(0 "F.Cu" signal "TOP")
		(4 "In1.Cu" signal "GND")
		(6 "In2.Cu" signal "IN1")
		(8 "In3.Cu" signal "GND1")
		(10 "In4.Cu" signal "IN2")
		(12 "In5.Cu" signal "GND2")
		(14 "In6.Cu" signal "IN3")
		(16 "In7.Cu" signal "GND3")
		(18 "In8.Cu" signal "VCC")
		(20 "In9.Cu" signal "VCC1")
		(22 "In10.Cu" signal "GND4")
		(24 "In11.Cu" signal "IN4")
		(26 "In12.Cu" signal "GND5")
		(28 "In13.Cu" signal "IN5")
		(30 "In14.Cu" signal "GND6")
		(32 "In15.Cu" signal "IN6")
		(34 "In16.Cu" signal "GND7")
		(2 "B.Cu" signal "BOTTOM")
		(9 "F.Adhes" user "F.Adhesive")
		(11 "B.Adhes" user "B.Adhesive")
		(13 "F.Paste" user "Package Geometry/Pastemask Top")
		(15 "B.Paste" user "Package Geometry/Pastemask Bottom")
		(5 "F.SilkS" user "Ref Des/Silkscreen Top")
		(7 "B.SilkS" user "Ref Des/Silkscreen Bottom")
		(1 "F.Mask" user "Board Geometry/Soldermask Top")
		(3 "B.Mask" user "Board Geometry/Soldermask Bottom")
		(17 "Dwgs.User" user "User.Drawings")
		(19 "Cmts.User" user "User.Comments")
		(21 "Eco1.User" user "User.Eco1")
		(23 "Eco2.User" user "User.Eco2")
		(25 "Edge.Cuts" user "Board Geometry/Outline")
		(27 "Margin" user)
		(31 "F.CrtYd" user "Package Geometry/Place Bound Top")
		(29 "B.CrtYd" user "Package Geometry/Place Bound Bottom")
		(35 "F.Fab" user "Ref Des/Assembly Top")
		(33 "B.Fab" user "Ref Des/Assembly Bottom")
	)
	(footprint ""
		(layer "B.Cu")
		(at 51.714908 -193.25971 -90)
		(property "Reference" "R260"
			(at 0 0 90)
			(layer "B.SilkS")
			(hide yes)
			(effects
				(font
					(size 1.27 1.27)
				)
				(justify mirror)
			)
		)
		(property "Value" ""
			(at 0 0 90)
			(layer "B.Fab")
			(effects
				(font
					(size 1.27 1.27)
				)
				(justify mirror)
			)
		)
		(duplicate_pad_numbers_are_jumpers no)
		(fp_line
			(start -0.7874 0.4064)
			(end 0.7874 0.4064)
			(stroke
				(width 0.1524)
				(type default)
			)
			(layer "B.SilkS")
		)
		(fp_line
			(start 0.7874 0.4064)
			(end 0.7874 -0.4064)
			(stroke
				(width 0.1524)
				(type default)
			)
			(layer "B.SilkS")
		)
		(fp_line
			(start -0.7874 -0.4064)
			(end -0.7874 0.4064)
			(stroke
				(width 0.1524)
				(type default)
			)
			(layer "B.SilkS")
		)
		(fp_line
			(start 0.7874 -0.4064)
			(end -0.7874 -0.4064)
			(stroke
				(width 0.1524)
				(type default)
			)
			(layer "B.SilkS")
		)
		(fp_line
			(start -0.67945 0.3048)
			(end -0.120396 0.3048)
			(stroke
				(width 0.1)
				(type default)
			)
			(layer "B.Fab")
		)
		(fp_line
			(start -0.120396 0.3048)
			(end -0.120396 0.2794)
			(stroke
				(width 0.1)
				(type default)
			)
			(layer "B.Fab")
		)
		(fp_line
			(start 0.12065 0.3048)
			(end 0.67945 0.3048)
			(stroke
				(width 0.1)
				(type default)
			)
			(layer "B.Fab")
		)
		(fp_line
			(start 0.67945 0.3048)
			(end 0.67945 -0.305054)
			(stroke
				(width 0.1)
				(type default)
			)
			(layer "B.Fab")
		)
		(fp_line
			(start -0.120396 0.2794)
			(end 0.12065 0.2794)
			(stroke
				(width 0.1)
				(type default)
			)
			(layer "B.Fab")
		)
		(fp_line
			(start 0.12065 0.2794)
			(end 0.12065 0.3048)
			(stroke
				(width 0.1)
				(type default)
			)
			(layer "B.Fab")
		)
		(fp_line
			(start -0.12065 -0.2794)
			(end -0.12065 -0.3048)
			(stroke
				(width 0.1)
				(type default)
			)
			(layer "B.Fab")
		)
		(fp_line
			(start 0.12065 -0.2794)
			(end -0.12065 -0.2794)
			(stroke
				(width 0.1)
				(type default)
			)
			(layer "B.Fab")
		)
		(fp_line
			(start -0.67945 -0.3048)
			(end -0.67945 0.3048)
			(stroke
				(width 0.1)
				(type default)
			)
			(layer "B.Fab")
		)
		(fp_line
			(start -0.12065 -0.3048)
			(end -0.67945 -0.3048)
			(stroke
				(width 0.1)
				(type default)
			)
			(layer "B.Fab")
		)
		(fp_line
			(start 0.12065 -0.305054)
			(end 0.12065 -0.2794)
			(stroke
				(width 0.1)
				(type default)
			)
			(layer "B.Fab")
		)
		(fp_line
			(start 0.67945 -0.305054)
			(end 0.12065 -0.305054)
			(stroke
				(width 0.1)
				(type default)
			)
			(layer "B.Fab")
		)
		(pad "1" smd circle
			(at 0.40005 0 90)
			(size 0 0)
			(layers "B.Cu" "B.Mask" "B.Paste")
			(net "PVNN_TERM_CPU1")
		)
		(pad "2" smd circle
			(at -0.40005 0 90)
			(size 0 0)
			(layers "B.Cu" "B.Mask" "B.Paste")
			(net "FM_S3M_CPU1_LVC1_GPIO_3")
		)
	)
	(footprint ""
		(layer "B.Cu")
		(at 155.031694 -36.950142 180)
		(property "Reference" "C2322"
			(at 0 0 0)
			(layer "B.SilkS")
			(hide yes)
			(effects
				(font
					(size 1.27 1.27)
				)
				(justify mirror)
			)
		)
		(property "Value" ""
			(at 0 0 0)
			(layer "B.Fab")
			(effects
				(font
					(size 1.27 1.27)
				)
				(justify mirror)
			)
		)
		(duplicate_pad_numbers_are_jumpers no)
		(fp_line
			(start 0.7874 0.4064)
			(end 0.7874 -0.4064)
			(stroke
				(width 0.1524)
				(type default)
			)
			(layer "B.SilkS")
		)
		(fp_line
			(start 0.7874 -0.4064)
			(end -0.7874 -0.4064)
			(stroke
				(width 0.1524)
				(type default)
			)
			(layer "B.SilkS")
		)
		(fp_line
			(start -0.7874 0.4064)
			(end 0.7874 0.4064)
			(stroke
				(width 0.1524)
				(type default)
			)
			(layer "B.SilkS")
		)
		(fp_line
			(start -0.7874 -0.4064)
			(end -0.7874 0.4064)
			(stroke
				(width 0.1524)
				(type default)
			)
			(layer "B.SilkS")
		)
		(fp_line
			(start 0.67945 0.3048)
			(end 0.67945 -0.305054)
			(stroke
				(width 0.1)
				(type default)
			)
			(layer "B.Fab")
		)
		(fp_line
			(start 0.67945 -0.305054)
			(end 0.12065 -0.305054)
			(stroke
				(width 0.1)
				(type default)
			)
			(layer "B.Fab")
		)
		(fp_line
			(start 0.12065 0.3048)
			(end 0.67945 0.3048)
			(stroke
				(width 0.1)
				(type default)
			)
			(layer "B.Fab")
		)
		(fp_line
			(start 0.12065 0.2794)
			(end 0.12065 0.3048)
			(stroke
				(width 0.1)
				(type default)
			)
			(layer "B.Fab")
		)
		(fp_line
			(start 0.12065 -0.2794)
			(end -0.12065 -0.2794)
			(stroke
				(width 0.1)
				(type default)
			)
			(layer "B.Fab")
		)
		(fp_line
			(start 0.12065 -0.305054)
			(end 0.12065 -0.2794)
			(stroke
				(width 0.1)
				(type default)
			)
			(layer "B.Fab")
		)
		(fp_line
			(start -0.120396 0.3048)
			(end -0.120396 0.2794)
			(stroke
				(width 0.1)
				(type default)
			)
			(layer "B.Fab")
		)
		(fp_line
			(start -0.120396 0.2794)
			(end 0.12065 0.2794)
			(stroke
				(width 0.1)
				(type default)
			)
			(layer "B.Fab")
		)
		(fp_line
			(start -0.12065 -0.2794)
			(end -0.12065 -0.3048)
			(stroke
				(width 0.1)
				(type default)
			)
			(layer "B.Fab")
		)
		(fp_line
			(start -0.12065 -0.3048)
			(end -0.67945 -0.3048)
			(stroke
				(width 0.1)
				(type default)
			)
			(layer "B.Fab")
		)
		(fp_line
			(start -0.67945 0.3048)
			(end -0.120396 0.3048)
			(stroke
				(width 0.1)
				(type default)
			)
			(layer "B.Fab")
		)
		(fp_line
			(start -0.67945 -0.3048)
			(end -0.67945 0.3048)
			(stroke
				(width 0.1)
				(type default)
			)
			(layer "B.Fab")
		)
		(pad "1" smd circle
			(at 0.40005 0)
			(size 0 0)
			(layers "B.Cu" "B.Mask" "B.Paste")
			(net "P3V3_AUX_USB_HUB_2")
		)
		(pad "2" smd circle
			(at -0.40005 0)
			(size 0 0)
			(layers "B.Cu" "B.Mask" "B.Paste")
			(net "GND")
		)
	)
	(footprint ""
		(layer "B.Cu")
		(at 337.218782 -64.315848 90)
		(property "Reference" "C169"
			(at 0 0 90)
			(layer "B.SilkS")
			(hide yes)
			(effects
				(font
					(size 1.27 1.27)
				)
				(justify mirror)
			)
		)
		(property "Value" ""
			(at 0 0 90)
			(layer "B.Fab")
			(effects
				(font
					(size 1.27 1.27)
				)
				(justify mirror)
			)
		)
		(duplicate_pad_numbers_are_jumpers no)
		(fp_line
			(start 0.299974 -0.150114)
			(end -0.299974 -0.150114)
			(stroke
				(width 0.1)
				(type default)
			)
			(layer "B.Fab")
		)
		(fp_line
			(start -0.299974 -0.150114)
			(end -0.299974 0.150114)
			(stroke
				(width 0.1)
				(type default)
			)
			(layer "B.Fab")
		)
		(fp_line
			(start 0.299974 0.150114)
			(end 0.299974 -0.150114)
			(stroke
				(width 0.1)
				(type default)
			)
			(layer "B.Fab")
		)
		(fp_line
			(start -0.299974 0.150114)
			(end 0.299974 0.150114)
			(stroke
				(width 0.1)
				(type default)
			)
			(layer "B.Fab")
		)
		(pad "1" smd rect
			(at 0.2667 0 270)
			(size 0.3048 0.381)
			(layers "B.Cu" "B.Mask" "B.Paste")
			(net "DMI_CPU0_PCH_RX_C_DN<0>")
		)
		(pad "2" smd rect
			(at -0.2667 0 270)
			(size 0.3048 0.381)
			(layers "B.Cu" "B.Mask" "B.Paste")
			(net "DMI_CPU0_PCH_RX_DN<0>")
		)
	)
)
